(kicad_pcb
	(version 20260206)
	(generator "pcbnew")
	(generator_version "10.0")
	(general
		(thickness 1.6)
		(legacy_teardrops no)
	)
	(paper "A4")
	(title_block
		(title "v1-pdb — T6M_PDB_D_0927_0900.brd")
		(comment 1 "Open CloudServer (Microsoft) / footprints 86-88 of 321")
	)
	(layers
		(0 "F.Cu" signal "TOP")
		(4 "In1.Cu" signal "GND")
		(6 "In2.Cu" signal "IN1")
		(8 "In3.Cu" signal "VCC")
		(10 "In4.Cu" signal "VCC1")
		(12 "In5.Cu" signal "IN2")
		(14 "In6.Cu" signal "GND1")
		(2 "B.Cu" signal "BOTTOM")
		(9 "F.Adhes" user "F.Adhesive")
		(11 "B.Adhes" user "B.Adhesive")
		(13 "F.Paste" user "Package Geometry/Pastemask Top")
		(15 "B.Paste" user "Package Geometry/Pastemask Bottom")
		(5 "F.SilkS" user "Ref Des/Silkscreen Top")
		(7 "B.SilkS" user "Ref Des/Silkscreen Bottom")
		(1 "F.Mask" user "Board Geometry/Soldermask Top")
		(3 "B.Mask" user "Board Geometry/Soldermask Bottom")
		(17 "Dwgs.User" user "User.Drawings")
		(19 "Cmts.User" user "User.Comments")
		(21 "Eco1.User" user "User.Eco1")
		(23 "Eco2.User" user "User.Eco2")
		(25 "Edge.Cuts" user "Board Geometry/Outline")
		(27 "Margin" user)
		(31 "F.CrtYd" user "Package Geometry/Place Bound Top")
		(29 "B.CrtYd" user "Package Geometry/Place Bound Bottom")
		(35 "F.Fab" user "Ref Des/Assembly Top")
		(33 "B.Fab" user "Ref Des/Assembly Bottom")
	)
	(footprint ""
		(layer "F.Cu")
		(at 73.00468 -42.631106 90)
		(property "Reference" "C13"
			(at -1.139444 4.766056 90)
			(unlocked yes)
			(layer "F.SilkS")
			(effects
				(font
					(size 0.7874 0.5842)
					(thickness 0.1524)
				)
				(justify left)
			)
		)
		(property "Value" ""
			(at 0 0 90)
			(layer "F.Fab")
			(effects
				(font
					(size 1.27 1.27)
				)
			)
		)
		(duplicate_pad_numbers_are_jumpers no)
		(fp_line
			(start 0.7874 -0.4064)
			(end 0.7874 0.4064)
			(stroke
				(width 0.1524)
				(type default)
			)
			(layer "F.SilkS")
		)
		(fp_line
			(start -0.7874 -0.4064)
			(end 0.7874 -0.4064)
			(stroke
				(width 0.1524)
				(type default)
			)
			(layer "F.SilkS")
		)
		(fp_line
			(start 0 0.381)
			(end 0 -0.381)
			(stroke
				(width 0.1524)
				(type default)
			)
			(layer "F.SilkS")
		)
		(fp_line
			(start 0.7874 0.4064)
			(end -0.7874 0.4064)
			(stroke
				(width 0.1524)
				(type default)
			)
			(layer "F.SilkS")
		)
		(fp_line
			(start -0.7874 0.4064)
			(end -0.7874 -0.4064)
			(stroke
				(width 0.1524)
				(type default)
			)
			(layer "F.SilkS")
		)
		(fp_poly
			(pts
				(xy -0.5334 0.254) (xy -0.635 0.254) (xy -0.635 0.2286) (xy -0.635 -0.254) (xy -0.5334 -0.254) (xy -0.5334 -0.2794)
				(xy 0.5334 -0.2794) (xy 0.5334 -0.254) (xy 0.635 -0.254) (xy 0.635 0.254) (xy 0.5334 0.254) (xy 0.5334 0.2794)
				(xy -0.508 0.2794) (xy -0.5334 0.2794)
			)
			(stroke
				(width 0)
				(type default)
			)
			(fill no)
			(layer "F.CrtYd")
		)
		(pad "1" smd rect
			(at 0.40005 0 90)
			(size 0.4572 0.508)
			(layers "F.Cu" "F.Mask" "F.Paste")
			(net "P12V")
		)
		(pad "2" smd rect
			(at -0.40005 0 90)
			(size 0.4572 0.508)
			(layers "F.Cu" "F.Mask" "F.Paste")
			(net "GND")
		)
	)
	(footprint ""
		(layer "F.Cu")
		(at 77.993494 -384.526282 180)
		(property "Reference" "R128"
			(at 1.129792 -1.375156 0)
			(unlocked yes)
			(layer "F.SilkS")
			(effects
				(font
					(size 0.7874 0.5842)
					(thickness 0.1524)
				)
				(justify left)
			)
		)
		(property "Value" ""
			(at 0 0 180)
			(layer "F.Fab")
			(effects
				(font
					(size 1.27 1.27)
				)
			)
		)
		(duplicate_pad_numbers_are_jumpers no)
		(fp_line
			(start 0.7874 0.4064)
			(end -0.7874 0.4064)
			(stroke
				(width 0.1524)
				(type default)
			)
			(layer "F.SilkS")
		)
		(fp_line
			(start 0.7874 -0.4064)
			(end 0.7874 0.4064)
			(stroke
				(width 0.1524)
				(type default)
			)
			(layer "F.SilkS")
		)
		(fp_line
			(start -0.7874 0.4064)
			(end -0.7874 -0.4064)
			(stroke
				(width 0.1524)
				(type default)
			)
			(layer "F.SilkS")
		)
		(fp_line
			(start -0.7874 -0.4064)
			(end 0.7874 -0.4064)
			(stroke
				(width 0.1524)
				(type default)
			)
			(layer "F.SilkS")
		)
		(fp_poly
			(pts
				(xy -0.508 0.2794) (xy -0.508 0.2286) (xy -0.635 0.2286) (xy -0.635 -0.254) (xy -0.5334 -0.254)
				(xy -0.5334 -0.2794) (xy 0.5334 -0.2794) (xy 0.5334 -0.254) (xy 0.635 -0.254) (xy 0.635 0.254) (xy 0.5334 0.254)
				(xy 0.5334 0.2794)
			)
			(stroke
				(width 0)
				(type default)
			)
			(fill no)
			(layer "F.CrtYd")
		)
		(pad "1" smd rect
			(at 0.40005 0 180)
			(size 0.4572 0.508)
			(layers "F.Cu" "F.Mask" "F.Paste")
			(net "PSU5_REMOTE_R2_N")
		)
		(pad "2" smd rect
			(at -0.40005 0 180)
			(size 0.4572 0.508)
			(layers "F.Cu" "F.Mask" "F.Paste")
			(net "GND")
		)
	)
	(footprint ""
		(layer "F.Cu")
		(at 76.120498 -14.939772 -90)
		(property "Reference" "C2"
			(at -1.75133 0.044704 90)
			(unlocked yes)
			(layer "F.SilkS")
			(effects
				(font
					(size 0.7874 0.5842)
					(thickness 0.1524)
				)
				(justify left)
			)
		)
		(property "Value" ""
			(at 0 0 270)
			(layer "F.Fab")
			(effects
				(font
					(size 1.27 1.27)
				)
			)
		)
		(duplicate_pad_numbers_are_jumpers no)
		(fp_line
			(start -0.7874 0.4064)
			(end -0.7874 -0.4064)
			(stroke
				(width 0.1524)
				(type default)
			)
			(layer "F.SilkS")
		)
		(fp_line
			(start 0.7874 0.4064)
			(end -0.7874 0.4064)
			(stroke
				(width 0.1524)
				(type default)
			)
			(layer "F.SilkS")
		)
		(fp_line
			(start 0 0.381)
			(end 0 -0.381)
			(stroke
				(width 0.1524)
				(type default)
			)
			(layer "F.SilkS")
		)
		(fp_line
			(start -0.7874 -0.4064)
			(end 0.7874 -0.4064)
			(stroke
				(width 0.1524)
				(type default)
			)
			(layer "F.SilkS")
		)
		(fp_line
			(start 0.7874 -0.4064)
			(end 0.7874 0.4064)
			(stroke
				(width 0.1524)
				(type default)
			)
			(layer "F.SilkS")
		)
		(fp_poly
			(pts
				(xy -0.5334 0.254) (xy -0.635 0.254) (xy -0.635 0.2286) (xy -0.635 -0.254) (xy -0.5334 -0.254) (xy -0.5334 -0.2794)
				(xy 0.5334 -0.2794) (xy 0.5334 -0.254) (xy 0.635 -0.254) (xy 0.635 0.254) (xy 0.5334 0.254) (xy 0.5334 0.2794)
				(xy -0.508 0.2794) (xy -0.5334 0.2794)
			)
			(stroke
				(width 0)
				(type default)
			)
			(fill no)
			(layer "F.CrtYd")
		)
		(pad "1" smd rect
			(at 0.40005 0 270)
			(size 0.4572 0.508)
			(layers "F.Cu" "F.Mask" "F.Paste")
			(net "P12V")
		)
		(pad "2" smd rect
			(at -0.40005 0 270)
			(size 0.4572 0.508)
			(layers "F.Cu" "F.Mask" "F.Paste")
			(net "GND")
		)
	)
)
